(kicad_pcb
	(version 20260206)
	(generator "pcbnew")
	(generator_version "10.0")
	(general
		(thickness 1.6)
		(legacy_teardrops no)
	)
	(paper "A4")
	(title_block
		(title "peb — Lightning_PEB_BRD.brd")
		(comment 1 "Lightning (Wiwynn / Facebook NVMe JBOF) / footprint 1445 of 2563 (U1), pads 118-234 of 1311")
	)
	(layers
		(0 "F.Cu" signal "TOP")
		(4 "In1.Cu" signal "L2GND")
		(6 "In2.Cu" signal "L3")
		(8 "In3.Cu" signal "L4VCC")
		(10 "In4.Cu" signal "L5VCC")
		(12 "In5.Cu" signal "L6")
		(14 "In6.Cu" signal "L7GND")
		(2 "B.Cu" signal "BOTTOM")
		(9 "F.Adhes" user "F.Adhesive")
		(11 "B.Adhes" user "B.Adhesive")
		(13 "F.Paste" user "Package Geometry/Pastemask Top")
		(15 "B.Paste" user "Package Geometry/Pastemask Bottom")
		(5 "F.SilkS" user "Ref Des/Silkscreen Top")
		(7 "B.SilkS" user "Ref Des/Silkscreen Bottom")
		(1 "F.Mask" user "Board Geometry/Soldermask Top")
		(3 "B.Mask" user "Board Geometry/Soldermask Bottom")
		(17 "Dwgs.User" user "User.Drawings")
		(19 "Cmts.User" user "User.Comments")
		(21 "Eco1.User" user "User.Eco1")
		(23 "Eco2.User" user "User.Eco2")
		(25 "Edge.Cuts" user "Board Geometry/Outline")
		(27 "Margin" user)
		(31 "F.CrtYd" user "Package Geometry/Place Bound Top")
		(29 "B.CrtYd" user "Package Geometry/Place Bound Bottom")
		(35 "F.Fab" user "Ref Des/Assembly Top")
		(33 "B.Fab" user "Ref Des/Assembly Bottom")
	)
	(footprint ""
		(layer "F.Cu")
		(at 240.599976 -47.999904 -90)
		(property "Reference" "U1"
			(at 0 0 270)
			(layer "F.SilkS")
			(hide yes)
			(effects
				(font
					(size 1.27 1.27)
				)
			)
		)
		(property "Value" "PM8546A-FEIP-GP"
			(at -25.785064 -6.40334 270)
			(unlocked yes)
			(layer "F.Fab")
			(hide yes)
			(effects
				(font
					(size 1.016 1.016)
					(thickness 0.1524)
				)
			)
		)
		(property "Device Type" "BGA1311C37D5H134"
			(at -25.785064 -7.92734 270)
			(unlocked yes)
			(layer "F.Fab")
			(hide yes)
			(effects
				(font
					(size 1.016 1.016)
					(thickness 0.1524)
				)
			)
		)
		(duplicate_pad_numbers_are_jumpers no)
		(pad "AC23" smd circle
			(at 3.999992 3.999992 270)
			(size 0.4572 0.4572)
			(layers "F.Cu" "F.Mask" "F.Paste")
			(net "GND")
		)
		(pad "AC24" smd circle
			(at 4.99999 3.999992 270)
			(size 0.4572 0.4572)
			(layers "F.Cu" "F.Mask" "F.Paste")
			(net "DUT_VDD")
		)
		(pad "AC25" smd circle
			(at 5.999988 3.999992 270)
			(size 0.4572 0.4572)
			(layers "F.Cu" "F.Mask" "F.Paste")
			(net "GND")
		)
		(pad "AC26" smd circle
			(at 6.999986 3.999992 270)
			(size 0.4572 0.4572)
			(layers "F.Cu" "F.Mask" "F.Paste")
			(net "DUT_AVD_PCIE")
		)
		(pad "AC27" smd circle
			(at 7.999984 3.999992 270)
			(size 0.4572 0.4572)
			(layers "F.Cu" "F.Mask" "F.Paste")
			(net "LBI_ADDR_4_R")
		)
		(pad "AC28" smd circle
			(at 8.999982 3.999992 270)
			(size 0.4572 0.4572)
			(layers "F.Cu" "F.Mask" "F.Paste")
			(net "LBI_ADDR_3_R")
		)
		(pad "AC29" smd circle
			(at 9.99998 3.999992 270)
			(size 0.4572 0.4572)
			(layers "F.Cu" "F.Mask" "F.Paste")
			(net "PCIE_REFCLK_H3_P")
		)
		(pad "AC30" smd circle
			(at 10.999978 3.999992 270)
			(size 0.4572 0.4572)
			(layers "F.Cu" "F.Mask" "F.Paste")
			(net "PCIE_REFCLK_H3_N")
		)
		(pad "AC31" smd circle
			(at 11.999976 3.999992 270)
			(size 0.4572 0.4572)
			(layers "F.Cu" "F.Mask" "F.Paste")
			(net "LBI_ADDR_2_R")
		)
		(pad "AC32" smd circle
			(at 12.999974 3.999992 270)
			(size 0.4572 0.4572)
			(layers "F.Cu" "F.Mask" "F.Paste")
			(net "PCIE_REFCLK_S4_P")
		)
		(pad "AC33" smd circle
			(at 13.999972 3.999992 270)
			(size 0.4572 0.4572)
			(layers "F.Cu" "F.Mask" "F.Paste")
			(net "PCIE_REFCLK_S4_N")
		)
		(pad "AC34" smd circle
			(at 14.99997 3.999992 270)
			(size 0.4572 0.4572)
			(layers "F.Cu" "F.Mask" "F.Paste")
			(net "DUT_VDDO")
		)
		(pad "AC35" smd circle
			(at 15.999968 3.999992 270)
			(size 0.4572 0.4572)
			(layers "F.Cu" "F.Mask" "F.Paste")
			(net "GND")
		)
		(pad "AC36" smd circle
			(at 16.999966 3.999992 270)
			(size 0.4572 0.4572)
			(layers "F.Cu" "F.Mask" "F.Paste")
			(net "PCIE_RX_P93")
		)
		(pad "AC37" smd circle
			(at 17.999964 3.999992 270)
			(size 0.4572 0.4572)
			(layers "F.Cu" "F.Mask" "F.Paste")
			(net "PCIE_RX_N93")
		)
		(pad "AD2" smd circle
			(at -16.999966 4.99999 270)
			(size 0.4572 0.4572)
			(layers "F.Cu" "F.Mask" "F.Paste")
			(net "PCIE_TX_CAP_N52")
		)
		(pad "AD3" smd circle
			(at -15.999968 4.99999 270)
			(size 0.4572 0.4572)
			(layers "F.Cu" "F.Mask" "F.Paste")
			(net "PCIE_TX_CAP_P52")
		)
		(pad "AD4" smd circle
			(at -14.99997 4.99999 270)
			(size 0.4572 0.4572)
			(layers "F.Cu" "F.Mask" "F.Paste")
			(net "GND")
		)
		(pad "AD5" smd circle
			(at -13.999972 4.99999 270)
			(size 0.4572 0.4572)
			(layers "F.Cu" "F.Mask" "F.Paste")
			(net "PCIE_RX_N52")
		)
		(pad "AD6" smd circle
			(at -12.999974 4.99999 270)
			(size 0.4572 0.4572)
			(layers "F.Cu" "F.Mask" "F.Paste")
			(net "PCIE_RX_P52")
		)
		(pad "AD7" smd circle
			(at -11.999976 4.99999 270)
			(size 0.4572 0.4572)
			(layers "F.Cu" "F.Mask" "F.Paste")
			(net "GND")
		)
		(pad "AD8" smd circle
			(at -10.999978 4.99999 270)
			(size 0.4572 0.4572)
			(layers "F.Cu" "F.Mask" "F.Paste")
			(net "DUT_AVD_TX")
		)
		(pad "AD9" smd circle
			(at -9.99998 4.99999 270)
			(size 0.4572 0.4572)
			(layers "F.Cu" "F.Mask" "F.Paste")
			(net "GND")
		)
		(pad "AD10" smd circle
			(at -8.999982 4.99999 270)
			(size 0.4572 0.4572)
			(layers "F.Cu" "F.Mask" "F.Paste")
			(net "DUT_AVD_TX")
		)
		(pad "AD11" smd circle
			(at -7.999984 4.99999 270)
			(size 0.4572 0.4572)
			(layers "F.Cu" "F.Mask" "F.Paste")
			(net "GND")
		)
		(pad "AD12" smd circle
			(at -6.999986 4.99999 270)
			(size 0.4572 0.4572)
			(layers "F.Cu" "F.Mask" "F.Paste")
			(net "GND")
		)
		(pad "AD13" smd circle
			(at -5.999988 4.99999 270)
			(size 0.4572 0.4572)
			(layers "F.Cu" "F.Mask" "F.Paste")
			(net "DUT_VDD")
		)
		(pad "AD14" smd circle
			(at -4.99999 4.99999 270)
			(size 0.4572 0.4572)
			(layers "F.Cu" "F.Mask" "F.Paste")
			(net "GND")
		)
		(pad "AD15" smd circle
			(at -3.999992 4.99999 270)
			(size 0.4572 0.4572)
			(layers "F.Cu" "F.Mask" "F.Paste")
			(net "DUT_VDD")
		)
		(pad "AD16" smd circle
			(at -2.999994 4.99999 270)
			(size 0.4572 0.4572)
			(layers "F.Cu" "F.Mask" "F.Paste")
			(net "GND")
		)
		(pad "AD17" smd circle
			(at -1.999996 4.99999 270)
			(size 0.4572 0.4572)
			(layers "F.Cu" "F.Mask" "F.Paste")
			(net "DUT_VDD")
		)
		(pad "AD18" smd circle
			(at -0.999998 4.99999 270)
			(size 0.4572 0.4572)
			(layers "F.Cu" "F.Mask" "F.Paste")
			(net "GND")
		)
		(pad "AD19" smd circle
			(at 0 4.99999 270)
			(size 0.4572 0.4572)
			(layers "F.Cu" "F.Mask" "F.Paste")
			(net "DUT_VDD")
		)
		(pad "AD20" smd circle
			(at 0.999998 4.99999 270)
			(size 0.4572 0.4572)
			(layers "F.Cu" "F.Mask" "F.Paste")
			(net "GND")
		)
		(pad "AD21" smd circle
			(at 1.999996 4.99999 270)
			(size 0.4572 0.4572)
			(layers "F.Cu" "F.Mask" "F.Paste")
			(net "DUT_VDD")
		)
		(pad "AD22" smd circle
			(at 2.999994 4.99999 270)
			(size 0.4572 0.4572)
			(layers "F.Cu" "F.Mask" "F.Paste")
			(net "GND")
		)
		(pad "AD23" smd circle
			(at 3.999992 4.99999 270)
			(size 0.4572 0.4572)
			(layers "F.Cu" "F.Mask" "F.Paste")
			(net "DUT_VDD")
		)
		(pad "AD24" smd circle
			(at 4.99999 4.99999 270)
			(size 0.4572 0.4572)
			(layers "F.Cu" "F.Mask" "F.Paste")
			(net "GND")
		)
		(pad "AD25" smd circle
			(at 5.999988 4.99999 270)
			(size 0.4572 0.4572)
			(layers "F.Cu" "F.Mask" "F.Paste")
			(net "DUT_VDD")
		)
		(pad "AD26" smd circle
			(at 6.999986 4.99999 270)
			(size 0.4572 0.4572)
			(layers "F.Cu" "F.Mask" "F.Paste")
			(net "GND")
		)
		(pad "AD27" smd circle
			(at 7.999984 4.99999 270)
			(size 0.4572 0.4572)
			(layers "F.Cu" "F.Mask" "F.Paste")
			(net "LBI_ADDR_8")
		)
		(pad "AD28" smd circle
			(at 8.999982 4.99999 270)
			(size 0.4572 0.4572)
			(layers "F.Cu" "F.Mask" "F.Paste")
			(net "DUT_VDDO")
		)
		(pad "AD29" smd circle
			(at 9.99998 4.99999 270)
			(size 0.4572 0.4572)
			(layers "F.Cu" "F.Mask" "F.Paste")
			(net "LBI_ADDR_7_R")
		)
		(pad "AD30" smd circle
			(at 10.999978 4.99999 270)
			(size 0.4572 0.4572)
			(layers "F.Cu" "F.Mask" "F.Paste")
			(net "LBI_ADDR_6_R")
		)
		(pad "AD31" smd circle
			(at 11.999976 4.99999 270)
			(size 0.4572 0.4572)
			(layers "F.Cu" "F.Mask" "F.Paste")
			(net "LBI_ADDR_5_R")
		)
		(pad "AD32" smd circle
			(at 12.999974 4.99999 270)
			(size 0.4572 0.4572)
			(layers "F.Cu" "F.Mask" "F.Paste")
			(net "PCIE_REFCLK_S5_P")
		)
		(pad "AD33" smd circle
			(at 13.999972 4.99999 270)
			(size 0.4572 0.4572)
			(layers "F.Cu" "F.Mask" "F.Paste")
			(net "PCIE_REFCLK_S5_N")
		)
		(pad "AD34" smd circle
			(at 14.99997 4.99999 270)
			(size 0.4572 0.4572)
			(layers "F.Cu" "F.Mask" "F.Paste")
			(net "GND")
		)
		(pad "AD35" smd circle
			(at 15.999968 4.99999 270)
			(size 0.4572 0.4572)
			(layers "F.Cu" "F.Mask" "F.Paste")
			(net "PCIE_RX_P92")
		)
		(pad "AD36" smd circle
			(at 16.999966 4.99999 270)
			(size 0.4572 0.4572)
			(layers "F.Cu" "F.Mask" "F.Paste")
			(net "PCIE_RX_N92")
		)
		(pad "AE1" smd circle
			(at -17.999964 5.999988 270)
			(size 0.4572 0.4572)
			(layers "F.Cu" "F.Mask" "F.Paste")
			(net "PCIE_TX_CAP_N53")
		)
		(pad "AE2" smd circle
			(at -16.999966 5.999988 270)
			(size 0.4572 0.4572)
			(layers "F.Cu" "F.Mask" "F.Paste")
			(net "PCIE_TX_CAP_P53")
		)
		(pad "AE3" smd circle
			(at -15.999968 5.999988 270)
			(size 0.4572 0.4572)
			(layers "F.Cu" "F.Mask" "F.Paste")
			(net "GND")
		)
		(pad "AE4" smd circle
			(at -14.99997 5.999988 270)
			(size 0.4572 0.4572)
			(layers "F.Cu" "F.Mask" "F.Paste")
			(net "PCIE_RX_N53")
		)
		(pad "AE5" smd circle
			(at -13.999972 5.999988 270)
			(size 0.4572 0.4572)
			(layers "F.Cu" "F.Mask" "F.Paste")
			(net "PCIE_RX_P53")
		)
		(pad "AE6" smd circle
			(at -12.999974 5.999988 270)
			(size 0.4572 0.4572)
			(layers "F.Cu" "F.Mask" "F.Paste")
			(net "GND")
		)
		(pad "AE7" smd circle
			(at -11.999976 5.999988 270)
			(size 0.4572 0.4572)
			(layers "F.Cu" "F.Mask" "F.Paste")
			(net "DUT_AVD_PCIE")
		)
		(pad "AE8" smd circle
			(at -10.999978 5.999988 270)
			(size 0.4572 0.4572)
			(layers "F.Cu" "F.Mask" "F.Paste")
			(net "GND")
		)
		(pad "AE9" smd circle
			(at -9.99998 5.999988 270)
			(size 0.4572 0.4572)
			(layers "F.Cu" "F.Mask" "F.Paste")
			(net "GND")
		)
		(pad "AE10" smd circle
			(at -8.999982 5.999988 270)
			(size 0.4572 0.4572)
			(layers "F.Cu" "F.Mask" "F.Paste")
			(net "GND")
		)
		(pad "AE11" smd circle
			(at -7.999984 5.999988 270)
			(size 0.4572 0.4572)
			(layers "F.Cu" "F.Mask" "F.Paste")
			(net "GND")
		)
		(pad "AE12" smd circle
			(at -6.999986 5.999988 270)
			(size 0.4572 0.4572)
			(layers "F.Cu" "F.Mask" "F.Paste")
			(net "GND")
		)
		(pad "AE13" smd circle
			(at -5.999988 5.999988 270)
			(size 0.4572 0.4572)
			(layers "F.Cu" "F.Mask" "F.Paste")
			(net "GND")
		)
		(pad "AE14" smd circle
			(at -4.99999 5.999988 270)
			(size 0.4572 0.4572)
			(layers "F.Cu" "F.Mask" "F.Paste")
			(net "DUT_VDD")
		)
		(pad "AE15" smd circle
			(at -3.999992 5.999988 270)
			(size 0.4572 0.4572)
			(layers "F.Cu" "F.Mask" "F.Paste")
			(net "GND")
		)
		(pad "AE16" smd circle
			(at -2.999994 5.999988 270)
			(size 0.4572 0.4572)
			(layers "F.Cu" "F.Mask" "F.Paste")
			(net "DUT_VDD")
		)
		(pad "AE17" smd circle
			(at -1.999996 5.999988 270)
			(size 0.4572 0.4572)
			(layers "F.Cu" "F.Mask" "F.Paste")
			(net "GND")
		)
		(pad "AE18" smd circle
			(at -0.999998 5.999988 270)
			(size 0.4572 0.4572)
			(layers "F.Cu" "F.Mask" "F.Paste")
			(net "DUT_VDD")
		)
		(pad "AE19" smd circle
			(at 0 5.999988 270)
			(size 0.4572 0.4572)
			(layers "F.Cu" "F.Mask" "F.Paste")
			(net "GND")
		)
		(pad "AE20" smd circle
			(at 0.999998 5.999988 270)
			(size 0.4572 0.4572)
			(layers "F.Cu" "F.Mask" "F.Paste")
			(net "DUT_VDD")
		)
		(pad "AE21" smd circle
			(at 1.999996 5.999988 270)
			(size 0.4572 0.4572)
			(layers "F.Cu" "F.Mask" "F.Paste")
			(net "GND")
		)
		(pad "AE22" smd circle
			(at 2.999994 5.999988 270)
			(size 0.4572 0.4572)
			(layers "F.Cu" "F.Mask" "F.Paste")
			(net "DUT_VDD")
		)
		(pad "AE23" smd circle
			(at 3.999992 5.999988 270)
			(size 0.4572 0.4572)
			(layers "F.Cu" "F.Mask" "F.Paste")
			(net "GND")
		)
		(pad "AE24" smd circle
			(at 4.99999 5.999988 270)
			(size 0.4572 0.4572)
			(layers "F.Cu" "F.Mask" "F.Paste")
			(net "DUT_VDD")
		)
		(pad "AE25" smd circle
			(at 5.999988 5.999988 270)
			(size 0.4572 0.4572)
			(layers "F.Cu" "F.Mask" "F.Paste")
			(net "GND")
		)
		(pad "AE26" smd circle
			(at 6.999986 5.999988 270)
			(size 0.4572 0.4572)
			(layers "F.Cu" "F.Mask" "F.Paste")
			(net "DUT_VDD")
		)
		(pad "AE27" smd circle
			(at 7.999984 5.999988 270)
			(size 0.4572 0.4572)
			(layers "F.Cu" "F.Mask" "F.Paste")
			(net "RMII_TX_EN")
		)
		(pad "AE28" smd circle
			(at 8.999982 5.999988 270)
			(size 0.4572 0.4572)
			(layers "F.Cu" "F.Mask" "F.Paste")
			(net "LBI_ADDR_12_R")
		)
		(pad "AE29" smd circle
			(at 9.99998 5.999988 270)
			(size 0.4572 0.4572)
			(layers "F.Cu" "F.Mask" "F.Paste")
			(net "GND")
		)
		(pad "AE30" smd circle
			(at 10.999978 5.999988 270)
			(size 0.4572 0.4572)
			(layers "F.Cu" "F.Mask" "F.Paste")
			(net "Net_325")
		)
		(pad "AE31" smd circle
			(at 11.999976 5.999988 270)
			(size 0.4572 0.4572)
			(layers "F.Cu" "F.Mask" "F.Paste")
			(net "LBI_ADDR_10")
		)
		(pad "AE32" smd circle
			(at 12.999974 5.999988 270)
			(size 0.4572 0.4572)
			(layers "F.Cu" "F.Mask" "F.Paste")
			(net "GND")
		)
		(pad "AE33" smd circle
			(at 13.999972 5.999988 270)
			(size 0.4572 0.4572)
			(layers "F.Cu" "F.Mask" "F.Paste")
			(net "LBI_ADDR_9")
		)
		(pad "AE34" smd circle
			(at 14.99997 5.999988 270)
			(size 0.4572 0.4572)
			(layers "F.Cu" "F.Mask" "F.Paste")
			(net "DUT_VDDO")
		)
		(pad "AE35" smd circle
			(at 15.999968 5.999988 270)
			(size 0.4572 0.4572)
			(layers "F.Cu" "F.Mask" "F.Paste")
			(net "GND")
		)
		(pad "AE36" smd circle
			(at 16.999966 5.999988 270)
			(size 0.4572 0.4572)
			(layers "F.Cu" "F.Mask" "F.Paste")
			(net "PCIE_RX_P91")
		)
		(pad "AE37" smd circle
			(at 17.999964 5.999988 270)
			(size 0.4572 0.4572)
			(layers "F.Cu" "F.Mask" "F.Paste")
			(net "PCIE_RX_N91")
		)
		(pad "AF2" smd circle
			(at -16.999966 6.999986 270)
			(size 0.4572 0.4572)
			(layers "F.Cu" "F.Mask" "F.Paste")
			(net "PCIE_TX_CAP_N54")
		)
		(pad "AF3" smd circle
			(at -15.999968 6.999986 270)
			(size 0.4572 0.4572)
			(layers "F.Cu" "F.Mask" "F.Paste")
			(net "PCIE_TX_CAP_P54")
		)
		(pad "AF4" smd circle
			(at -14.99997 6.999986 270)
			(size 0.4572 0.4572)
			(layers "F.Cu" "F.Mask" "F.Paste")
			(net "GND")
		)
		(pad "AF5" smd circle
			(at -13.999972 6.999986 270)
			(size 0.4572 0.4572)
			(layers "F.Cu" "F.Mask" "F.Paste")
			(net "PCIE_RX_N54")
		)
		(pad "AF6" smd circle
			(at -12.999974 6.999986 270)
			(size 0.4572 0.4572)
			(layers "F.Cu" "F.Mask" "F.Paste")
			(net "PCIE_RX_P54")
		)
		(pad "AF7" smd circle
			(at -11.999976 6.999986 270)
			(size 0.4572 0.4572)
			(layers "F.Cu" "F.Mask" "F.Paste")
			(net "DUT_AVD_PCIE")
		)
		(pad "AF8" smd circle
			(at -10.999978 6.999986 270)
			(size 0.4572 0.4572)
			(layers "F.Cu" "F.Mask" "F.Paste")
			(net "GND")
		)
		(pad "AF9" smd circle
			(at -9.99998 6.999986 270)
			(size 0.4572 0.4572)
			(layers "F.Cu" "F.Mask" "F.Paste")
			(net "GND")
		)
		(pad "AF10" smd circle
			(at -8.999982 6.999986 270)
			(size 0.4572 0.4572)
			(layers "F.Cu" "F.Mask" "F.Paste")
			(net "GND")
		)
		(pad "AF11" smd circle
			(at -7.999984 6.999986 270)
			(size 0.4572 0.4572)
			(layers "F.Cu" "F.Mask" "F.Paste")
			(net "GND")
		)
		(pad "AF12" smd circle
			(at -6.999986 6.999986 270)
			(size 0.4572 0.4572)
			(layers "F.Cu" "F.Mask" "F.Paste")
			(net "GND")
		)
		(pad "AF13" smd circle
			(at -5.999988 6.999986 270)
			(size 0.4572 0.4572)
			(layers "F.Cu" "F.Mask" "F.Paste")
			(net "DUT_AVD_PCIE")
		)
		(pad "AF14" smd circle
			(at -4.99999 6.999986 270)
			(size 0.4572 0.4572)
			(layers "F.Cu" "F.Mask" "F.Paste")
			(net "GND")
		)
		(pad "AF15" smd circle
			(at -3.999992 6.999986 270)
			(size 0.4572 0.4572)
			(layers "F.Cu" "F.Mask" "F.Paste")
			(net "DUT_VDD")
		)
		(pad "AF16" smd circle
			(at -2.999994 6.999986 270)
			(size 0.4572 0.4572)
			(layers "F.Cu" "F.Mask" "F.Paste")
			(net "GND")
		)
		(pad "AF17" smd circle
			(at -1.999996 6.999986 270)
			(size 0.4572 0.4572)
			(layers "F.Cu" "F.Mask" "F.Paste")
			(net "DUT_VDD")
		)
		(pad "AF18" smd circle
			(at -0.999998 6.999986 270)
			(size 0.4572 0.4572)
			(layers "F.Cu" "F.Mask" "F.Paste")
			(net "GND")
		)
		(pad "AF19" smd circle
			(at 0 6.999986 270)
			(size 0.4572 0.4572)
			(layers "F.Cu" "F.Mask" "F.Paste")
			(net "DUT_VDD")
		)
		(pad "AF20" smd circle
			(at 0.999998 6.999986 270)
			(size 0.4572 0.4572)
			(layers "F.Cu" "F.Mask" "F.Paste")
			(net "GND")
		)
		(pad "AF21" smd circle
			(at 1.999996 6.999986 270)
			(size 0.4572 0.4572)
			(layers "F.Cu" "F.Mask" "F.Paste")
			(net "DUT_AVD_PCIE")
		)
		(pad "AF22" smd circle
			(at 2.999994 6.999986 270)
			(size 0.4572 0.4572)
			(layers "F.Cu" "F.Mask" "F.Paste")
			(net "GND")
		)
		(pad "AF23" smd circle
			(at 3.999992 6.999986 270)
			(size 0.4572 0.4572)
			(layers "F.Cu" "F.Mask" "F.Paste")
			(net "DUT_VDD")
		)
		(pad "AF24" smd circle
			(at 4.99999 6.999986 270)
			(size 0.4572 0.4572)
			(layers "F.Cu" "F.Mask" "F.Paste")
			(net "GND")
		)
		(pad "AF25" smd circle
			(at 5.999988 6.999986 270)
			(size 0.4572 0.4572)
			(layers "F.Cu" "F.Mask" "F.Paste")
			(net "DUT_VDD")
		)
		(pad "AF26" smd circle
			(at 6.999986 6.999986 270)
			(size 0.4572 0.4572)
			(layers "F.Cu" "F.Mask" "F.Paste")
			(net "EJTAG_TCK_R")
		)
		(pad "AF27" smd circle
			(at 7.999984 6.999986 270)
			(size 0.4572 0.4572)
			(layers "F.Cu" "F.Mask" "F.Paste")
			(net "RMII_CRS_DV")
		)
		(pad "AF28" smd circle
			(at 8.999982 6.999986 270)
			(size 0.4572 0.4572)
			(layers "F.Cu" "F.Mask" "F.Paste")
			(net "RMII_REF_CLK")
		)
		(pad "AF29" smd circle
			(at 9.99998 6.999986 270)
			(size 0.4572 0.4572)
			(layers "F.Cu" "F.Mask" "F.Paste")
			(net "RMII_RXD_1")
		)
		(pad "AF30" smd circle
			(at 10.999978 6.999986 270)
			(size 0.4572 0.4572)
			(layers "F.Cu" "F.Mask" "F.Paste")
			(net "RMII_RXD_0")
		)
		(pad "AF31" smd circle
			(at 11.999976 6.999986 270)
			(size 0.4572 0.4572)
			(layers "F.Cu" "F.Mask" "F.Paste")
			(net "RMII_RX_ER")
		)
	)
)
